# S9S_MB_2U (Grand Teton) — schematic netlist excerpt (pin names and nets, part order shuffled) for the footprints in the layout excerpt that follows; sources: Cadence DE-HDL packaged netlist, KiCad conversion of 03242023_DA0F0TMBIJ0_F0T_Motherboard_J_brd_V01_OCP.brd

R4137  Q_RES  4.7K 5% CHIP  pkg 0402LF  page 146 : A = P3V3_AUX ; B = GPU_3V3IO_RSVD3_FFU_N

Q118  MOSFET_NCH_DUAL  PJT138K EMPTY  pkg SOT363XD  page 162
  S1  = GND
  G1  = P12V_OCP_EN_2_R
  D2  = P12V_OCP_UV_2_R
  S2  = GND
  G2  = P12V_OCP_2_EN_G
  D1  = P12V_OCP_2_EN_G

(kicad_pcb
	(version 20260206)
	(generator "pcbnew")
	(generator_version "10.0")
	(general
		(thickness 1.6)
		(legacy_teardrops no)
	)
	(paper "A4")
	(title_block
		(title "03242023_DA0F0TMBIJ0_F0T_Motherboard_J_brd_V01_OCP.brd")
		(comment 1 "Grand Teton / footprints 3712-3713 of 6105")
	)
	(layers
		(0 "F.Cu" signal "TOP")
		(4 "In1.Cu" signal "GND")
		(6 "In2.Cu" signal "IN1")
		(8 "In3.Cu" signal "GND1")
		(10 "In4.Cu" signal "IN2")
		(12 "In5.Cu" signal "GND2")
		(14 "In6.Cu" signal "IN3")
		(16 "In7.Cu" signal "GND3")
		(18 "In8.Cu" signal "VCC")
		(20 "In9.Cu" signal "VCC1")
		(22 "In10.Cu" signal "GND4")
		(24 "In11.Cu" signal "IN4")
		(26 "In12.Cu" signal "GND5")
		(28 "In13.Cu" signal "IN5")
		(30 "In14.Cu" signal "GND6")
		(32 "In15.Cu" signal "IN6")
		(34 "In16.Cu" signal "GND7")
		(2 "B.Cu" signal "BOTTOM")
		(9 "F.Adhes" user "F.Adhesive")
		(11 "B.Adhes" user "B.Adhesive")
		(13 "F.Paste" user "Package Geometry/Pastemask Top")
		(15 "B.Paste" user "Package Geometry/Pastemask Bottom")
		(5 "F.SilkS" user "Ref Des/Silkscreen Top")
		(7 "B.SilkS" user "Ref Des/Silkscreen Bottom")
		(1 "F.Mask" user "Board Geometry/Soldermask Top")
		(3 "B.Mask" user "Board Geometry/Soldermask Bottom")
		(17 "Dwgs.User" user "User.Drawings")
		(19 "Cmts.User" user "User.Comments")
		(21 "Eco1.User" user "User.Eco1")
		(23 "Eco2.User" user "User.Eco2")
		(25 "Edge.Cuts" user "Board Geometry/Outline")
		(27 "Margin" user)
		(31 "F.CrtYd" user "Package Geometry/Place Bound Top")
		(29 "B.CrtYd" user "Package Geometry/Place Bound Bottom")
		(35 "F.Fab" user "Ref Des/Assembly Top")
		(33 "B.Fab" user "Ref Des/Assembly Bottom")
	)
	(footprint ""
		(layer "F.Cu")
		(at 62.47257 -37.307266 180)
		(property "Reference" "Q118"
			(at 0.51435 -2.215388 0)
			(unlocked yes)
			(layer "F.SilkS")
			(effects
				(font
					(size 0.7874 0.5842)
					(thickness 0.1524)
				)
				(justify left)
			)
		)
		(property "Value" ""
			(at 0 0 180)
			(layer "F.Fab")
			(effects
				(font
					(size 1.27 1.27)
				)
			)
		)
		(duplicate_pad_numbers_are_jumpers no)
		(fp_line
			(start 1.332738 1.100074)
			(end -1.332738 1.100074)
			(stroke
				(width 0.1524)
				(type default)
			)
			(layer "F.SilkS")
		)
		(fp_line
			(start 1.332738 -1.100074)
			(end 1.332738 1.100074)
			(stroke
				(width 0.1524)
				(type default)
			)
			(layer "F.SilkS")
		)
		(fp_line
			(start 0.4826 -1.100074)
			(end 1.332738 -1.100074)
			(stroke
				(width 0.1524)
				(type default)
			)
			(layer "F.SilkS")
		)
		(fp_line
			(start 0 -0.541274)
			(end 0.4826 -1.100074)
			(stroke
				(width 0.1524)
				(type default)
			)
			(layer "F.SilkS")
		)
		(fp_line
			(start -0.4826 -1.100074)
			(end 0 -0.541274)
			(stroke
				(width 0.1524)
				(type default)
			)
			(layer "F.SilkS")
		)
		(fp_line
			(start -1.332738 1.100074)
			(end -1.332738 -1.100074)
			(stroke
				(width 0.1524)
				(type default)
			)
			(layer "F.SilkS")
		)
		(fp_line
			(start -1.332738 -1.100074)
			(end -0.4826 -1.100074)
			(stroke
				(width 0.1524)
				(type default)
			)
			(layer "F.SilkS")
		)
		(fp_poly
			(pts
				(xy -2.7432 -1.011174) (xy -2.041144 -0.660146) (xy -2.7432 -0.309118)
			)
			(stroke
				(width 0)
				(type default)
			)
			(fill yes)
			(layer "F.SilkS")
		)
		(fp_line
			(start 0.674878 1.100074)
			(end -0.674878 1.100074)
			(stroke
				(width 0.1)
				(type default)
			)
			(layer "F.Fab")
		)
		(fp_line
			(start 0.674878 -1.100074)
			(end 0.674878 1.100074)
			(stroke
				(width 0.1)
				(type default)
			)
			(layer "F.Fab")
		)
		(fp_line
			(start -0.674878 1.100074)
			(end -0.674878 -1.100074)
			(stroke
				(width 0.1)
				(type default)
			)
			(layer "F.Fab")
		)
		(fp_line
			(start -0.674878 -1.100074)
			(end 0.674878 -1.100074)
			(stroke
				(width 0.1)
				(type default)
			)
			(layer "F.Fab")
		)
		(fp_poly
			(pts
				(xy -2.2352 -0.298958) (xy -2.2352 -1.001014) (xy -1.533144 -0.649986)
			)
			(stroke
				(width 0)
				(type default)
			)
			(fill yes)
			(layer "F.Fab")
		)
		(pad "1" smd rect
			(at -0.94996 -0.649986 270)
			(size 0.4318 0.508)
			(layers "F.Cu" "F.Mask" "F.Paste")
			(net "GND")
		)
		(pad "2" smd rect
			(at -0.94996 0 270)
			(size 0.4318 0.508)
			(layers "F.Cu" "F.Mask" "F.Paste")
			(net "P12V_OCP_EN_2_R")
		)
		(pad "3" smd rect
			(at -0.94996 0.649986 270)
			(size 0.4318 0.508)
			(layers "F.Cu" "F.Mask" "F.Paste")
			(net "P12V_OCP_UV_2_R")
		)
		(pad "4" smd rect
			(at 0.94996 0.649986 270)
			(size 0.4318 0.508)
			(layers "F.Cu" "F.Mask" "F.Paste")
			(net "GND")
		)
		(pad "5" smd rect
			(at 0.94996 0 270)
			(size 0.4318 0.508)
			(layers "F.Cu" "F.Mask" "F.Paste")
			(net "P12V_OCP_2_EN_G")
		)
		(pad "6" smd rect
			(at 0.94996 -0.649986 270)
			(size 0.4318 0.508)
			(layers "F.Cu" "F.Mask" "F.Paste")
			(net "P12V_OCP_2_EN_G")
		)
	)
	(footprint ""
		(layer "F.Cu")
		(at 303.780444 -438.109106 -90)
		(property "Reference" "R4137"
			(at 0 0 270)
			(layer "F.SilkS")
			(hide yes)
			(effects
				(font
					(size 1.27 1.27)
				)
			)
		)
		(property "Value" ""
			(at 0 0 270)
			(layer "F.Fab")
			(effects
				(font
					(size 1.27 1.27)
				)
			)
		)
		(duplicate_pad_numbers_are_jumpers no)
		(fp_line
			(start -0.7874 0.4064)
			(end -0.7874 -0.4064)
			(stroke
				(width 0.1524)
				(type default)
			)
			(layer "F.SilkS")
		)
		(fp_line
			(start 0.7874 0.4064)
			(end -0.7874 0.4064)
			(stroke
				(width 0.1524)
				(type default)
			)
			(layer "F.SilkS")
		)
		(fp_line
			(start -0.7874 -0.4064)
			(end 0.7874 -0.4064)
			(stroke
				(width 0.1524)
				(type default)
			)
			(layer "F.SilkS")
		)
		(fp_line
			(start 0.7874 -0.4064)
			(end 0.7874 0.4064)
			(stroke
				(width 0.1524)
				(type default)
			)
			(layer "F.SilkS")
		)
		(fp_line
			(start -0.67945 0.3048)
			(end -0.67945 -0.305054)
			(stroke
				(width 0.1)
				(type default)
			)
			(layer "F.Fab")
		)
		(fp_line
			(start -0.12065 0.3048)
			(end -0.67945 0.3048)
			(stroke
				(width 0.1)
				(type default)
			)
			(layer "F.Fab")
		)
		(fp_line
			(start 0.120396 0.3048)
			(end 0.120396 0.2794)
			(stroke
				(width 0.1)
				(type default)
			)
			(layer "F.Fab")
		)
		(fp_line
			(start 0.67945 0.3048)
			(end 0.120396 0.3048)
			(stroke
				(width 0.1)
				(type default)
			)
			(layer "F.Fab")
		)
		(fp_line
			(start -0.12065 0.2794)
			(end -0.12065 0.3048)
			(stroke
				(width 0.1)
				(type default)
			)
			(layer "F.Fab")
		)
		(fp_line
			(start 0.120396 0.2794)
			(end -0.12065 0.2794)
			(stroke
				(width 0.1)
				(type default)
			)
			(layer "F.Fab")
		)
		(fp_line
			(start -0.12065 -0.2794)
			(end 0.12065 -0.2794)
			(stroke
				(width 0.1)
				(type default)
			)
			(layer "F.Fab")
		)
		(fp_line
			(start 0.12065 -0.2794)
			(end 0.12065 -0.3048)
			(stroke
				(width 0.1)
				(type default)
			)
			(layer "F.Fab")
		)
		(fp_line
			(start 0.12065 -0.3048)
			(end 0.67945 -0.3048)
			(stroke
				(width 0.1)
				(type default)
			)
			(layer "F.Fab")
		)
		(fp_line
			(start 0.67945 -0.3048)
			(end 0.67945 0.3048)
			(stroke
				(width 0.1)
				(type default)
			)
			(layer "F.Fab")
		)
		(fp_line
			(start -0.67945 -0.305054)
			(end -0.12065 -0.305054)
			(stroke
				(width 0.1)
				(type default)
			)
			(layer "F.Fab")
		)
		(fp_line
			(start -0.12065 -0.305054)
			(end -0.12065 -0.2794)
			(stroke
				(width 0.1)
				(type default)
			)
			(layer "F.Fab")
		)
		(pad "1" smd circle
			(at -0.40005 0 270)
			(size 0 0)
			(layers "F.Cu" "F.Mask" "F.Paste")
			(net "P3V3_AUX")
		)
		(pad "2" smd circle
			(at 0.40005 0 270)
			(size 0 0)
			(layers "F.Cu" "F.Mask" "F.Paste")
			(net "GPU_3V3IO_RSVD3_FFU_N")
		)
	)
)
